(kicad_pcb
	(version 20260206)
	(generator "pcbnew")
	(generator_version "10.0")
	(general
		(thickness 1.6)
		(legacy_teardrops no)
	)
	(paper "A4")
	(title_block
		(title "01162023_DA0F0TEBIF0_F0T_Expander_BD_F_brd_V02_OCP.brd")
		(comment 1 "Grand Teton / footprint 6619 of 9728 (PEX0), pads 1766-1880 of 2397")
	)
	(layers
		(0 "F.Cu" signal "TOP")
		(4 "In1.Cu" signal "GND")
		(6 "In2.Cu" signal "VCC")
		(8 "In3.Cu" signal "VCC1")
		(10 "In4.Cu" signal "GND1")
		(12 "In5.Cu" signal "IN1")
		(14 "In6.Cu" signal "GND2")
		(16 "In7.Cu" signal "IN2")
		(18 "In8.Cu" signal "GND3")
		(20 "In9.Cu" signal "IN3")
		(22 "In10.Cu" signal "GND4")
		(24 "In11.Cu" signal "IN4")
		(26 "In12.Cu" signal "GND5")
		(28 "In13.Cu" signal "IN5")
		(30 "In14.Cu" signal "GND6")
		(32 "In15.Cu" signal "IN6")
		(34 "In16.Cu" signal "GND7")
		(2 "B.Cu" signal "BOTTOM")
		(9 "F.Adhes" user "F.Adhesive")
		(11 "B.Adhes" user "B.Adhesive")
		(13 "F.Paste" user "Package Geometry/Pastemask Top")
		(15 "B.Paste" user "Package Geometry/Pastemask Bottom")
		(5 "F.SilkS" user "Ref Des/Silkscreen Top")
		(7 "B.SilkS" user "Ref Des/Silkscreen Bottom")
		(1 "F.Mask" user "Board Geometry/Soldermask Top")
		(3 "B.Mask" user "Board Geometry/Soldermask Bottom")
		(17 "Dwgs.User" user "User.Drawings")
		(19 "Cmts.User" user "User.Comments")
		(21 "Eco1.User" user "User.Eco1")
		(23 "Eco2.User" user "User.Eco2")
		(25 "Edge.Cuts" user "Board Geometry/Outline")
		(27 "Margin" user)
		(31 "F.CrtYd" user "Package Geometry/Place Bound Top")
		(29 "B.CrtYd" user "Package Geometry/Place Bound Bottom")
		(35 "F.Fab" user "Ref Des/Assembly Top")
		(33 "B.Fab" user "Ref Des/Assembly Bottom")
	)
	(footprint ""
		(layer "F.Cu")
		(at 59.649868 -295.89984)
		(property "Reference" "PEX0"
			(at -3.360166 35.566858 0)
			(unlocked yes)
			(layer "F.SilkS")
			(effects
				(font
					(size 2.032 1.524)
					(thickness 0.1524)
				)
				(justify left)
			)
		)
		(property "Value" ""
			(at 0 0 0)
			(layer "F.Fab")
			(effects
				(font
					(size 1.27 1.27)
				)
			)
		)
		(duplicate_pad_numbers_are_jumpers no)
		(pad "H6" smd circle
			(at -18.050002 -16.150082)
			(size 0.4572 0.4572)
			(layers "F.Cu" "F.Mask" "F.Paste")
			(net "P5E_PEX0_STN7_TX_DN<126>")
		)
		(pad "H7" smd circle
			(at -17.100042 -16.150082)
			(size 0.4572 0.4572)
			(layers "F.Cu" "F.Mask" "F.Paste")
			(net "GND")
		)
		(pad "H8" smd circle
			(at -16.150082 -16.150082)
			(size 0.4572 0.4572)
			(layers "F.Cu" "F.Mask" "F.Paste")
			(net "P5E_PEX0_STN6_TX_DN<111>")
		)
		(pad "H9" smd circle
			(at -15.200122 -16.150082)
			(size 0.4572 0.4572)
			(layers "F.Cu" "F.Mask" "F.Paste")
			(net "GND")
		)
		(pad "H10" smd circle
			(at -14.249908 -16.150082)
			(size 0.4572 0.4572)
			(layers "F.Cu" "F.Mask" "F.Paste")
			(net "P5E_PEX0_STN6_TX_DN<109>")
		)
		(pad "H11" smd circle
			(at -13.299948 -16.150082)
			(size 0.4572 0.4572)
			(layers "F.Cu" "F.Mask" "F.Paste")
			(net "GND")
		)
		(pad "H12" smd circle
			(at -12.349988 -16.150082)
			(size 0.4572 0.4572)
			(layers "F.Cu" "F.Mask" "F.Paste")
			(net "P5E_PEX0_STN6_TX_DN<107>")
		)
		(pad "H13" smd circle
			(at -11.400028 -16.150082)
			(size 0.4572 0.4572)
			(layers "F.Cu" "F.Mask" "F.Paste")
			(net "GND")
		)
		(pad "H14" smd circle
			(at -10.450068 -16.150082)
			(size 0.4572 0.4572)
			(layers "F.Cu" "F.Mask" "F.Paste")
			(net "P5E_PEX0_STN6_TX_DN<105>")
		)
		(pad "H15" smd circle
			(at -9.500108 -16.150082)
			(size 0.4572 0.4572)
			(layers "F.Cu" "F.Mask" "F.Paste")
			(net "GND")
		)
		(pad "H16" smd circle
			(at -8.549894 -16.150082)
			(size 0.4572 0.4572)
			(layers "F.Cu" "F.Mask" "F.Paste")
			(net "P5E_PEX0_STN6_TX_DN<103>")
		)
		(pad "H17" smd circle
			(at -7.599934 -16.150082)
			(size 0.4572 0.4572)
			(layers "F.Cu" "F.Mask" "F.Paste")
			(net "GND")
		)
		(pad "H18" smd circle
			(at -6.649974 -16.150082)
			(size 0.4572 0.4572)
			(layers "F.Cu" "F.Mask" "F.Paste")
			(net "P5E_PEX0_STN6_TX_DN<101>")
		)
		(pad "H19" smd circle
			(at -5.700014 -16.150082)
			(size 0.4572 0.4572)
			(layers "F.Cu" "F.Mask" "F.Paste")
			(net "GND")
		)
		(pad "H20" smd circle
			(at -4.750054 -16.150082)
			(size 0.4572 0.4572)
			(layers "F.Cu" "F.Mask" "F.Paste")
			(net "P5E_PEX0_STN6_TX_DN<99>")
		)
		(pad "H21" smd circle
			(at -3.800094 -16.150082)
			(size 0.4572 0.4572)
			(layers "F.Cu" "F.Mask" "F.Paste")
			(net "GND")
		)
		(pad "H22" smd circle
			(at -2.84988 -16.150082)
			(size 0.4572 0.4572)
			(layers "F.Cu" "F.Mask" "F.Paste")
			(net "P5E_PEX0_STN6_TX_DN<97>")
		)
		(pad "H23" smd circle
			(at -1.89992 -16.150082)
			(size 0.4572 0.4572)
			(layers "F.Cu" "F.Mask" "F.Paste")
			(net "GND")
		)
		(pad "H24" smd circle
			(at -0.94996 -16.150082)
			(size 0.4572 0.4572)
			(layers "F.Cu" "F.Mask" "F.Paste")
			(net "P5E_PEX0_STN5_TX_DN<80>")
		)
		(pad "H25" smd circle
			(at 0 -16.150082)
			(size 0.4572 0.4572)
			(layers "F.Cu" "F.Mask" "F.Paste")
			(net "GND")
		)
		(pad "H26" smd circle
			(at 0.94996 -16.150082)
			(size 0.4572 0.4572)
			(layers "F.Cu" "F.Mask" "F.Paste")
			(net "P5E_PEX0_STN5_TX_DN<82>")
		)
		(pad "H27" smd circle
			(at 1.89992 -16.150082)
			(size 0.4572 0.4572)
			(layers "F.Cu" "F.Mask" "F.Paste")
			(net "GND")
		)
		(pad "H28" smd circle
			(at 2.84988 -16.150082)
			(size 0.4572 0.4572)
			(layers "F.Cu" "F.Mask" "F.Paste")
			(net "P5E_PEX0_STN5_TX_DN<84>")
		)
		(pad "H29" smd circle
			(at 3.800094 -16.150082)
			(size 0.4572 0.4572)
			(layers "F.Cu" "F.Mask" "F.Paste")
			(net "GND")
		)
		(pad "H30" smd circle
			(at 4.750054 -16.150082)
			(size 0.4572 0.4572)
			(layers "F.Cu" "F.Mask" "F.Paste")
			(net "P5E_PEX0_STN5_TX_DN<86>")
		)
		(pad "H31" smd circle
			(at 5.700014 -16.150082)
			(size 0.4572 0.4572)
			(layers "F.Cu" "F.Mask" "F.Paste")
			(net "GND")
		)
		(pad "H32" smd circle
			(at 6.649974 -16.150082)
			(size 0.4572 0.4572)
			(layers "F.Cu" "F.Mask" "F.Paste")
			(net "P5E_PEX0_STN5_TX_DN<88>")
		)
		(pad "H33" smd circle
			(at 7.599934 -16.150082)
			(size 0.4572 0.4572)
			(layers "F.Cu" "F.Mask" "F.Paste")
			(net "GND")
		)
		(pad "H34" smd circle
			(at 8.549894 -16.150082)
			(size 0.4572 0.4572)
			(layers "F.Cu" "F.Mask" "F.Paste")
			(net "P5E_PEX0_STN5_TX_DN<90>")
		)
		(pad "H35" smd circle
			(at 9.500108 -16.150082)
			(size 0.4572 0.4572)
			(layers "F.Cu" "F.Mask" "F.Paste")
			(net "GND")
		)
		(pad "H36" smd circle
			(at 10.450068 -16.150082)
			(size 0.4572 0.4572)
			(layers "F.Cu" "F.Mask" "F.Paste")
			(net "P5E_PEX0_STN5_TX_DN<92>")
		)
		(pad "H37" smd circle
			(at 11.400028 -16.150082)
			(size 0.4572 0.4572)
			(layers "F.Cu" "F.Mask" "F.Paste")
			(net "GND")
		)
		(pad "H38" smd circle
			(at 12.349988 -16.150082)
			(size 0.4572 0.4572)
			(layers "F.Cu" "F.Mask" "F.Paste")
			(net "P5E_PEX0_STN5_TX_DN<94>")
		)
		(pad "H39" smd circle
			(at 13.299948 -16.150082)
			(size 0.4572 0.4572)
			(layers "F.Cu" "F.Mask" "F.Paste")
			(net "GND")
		)
		(pad "H40" smd circle
			(at 14.249908 -16.150082)
			(size 0.4572 0.4572)
			(layers "F.Cu" "F.Mask" "F.Paste")
			(net "P5E_PEX0_STN4_TX_DN<79>")
		)
		(pad "H41" smd circle
			(at 15.200122 -16.150082)
			(size 0.4572 0.4572)
			(layers "F.Cu" "F.Mask" "F.Paste")
			(net "GND")
		)
		(pad "H42" smd circle
			(at 16.150082 -16.150082)
			(size 0.4572 0.4572)
			(layers "F.Cu" "F.Mask" "F.Paste")
			(net "P5E_PEX0_STN4_TX_DN<77>")
		)
		(pad "H43" smd circle
			(at 17.100042 -16.150082)
			(size 0.4572 0.4572)
			(layers "F.Cu" "F.Mask" "F.Paste")
			(net "GND")
		)
		(pad "H44" smd circle
			(at 18.050002 -16.150082)
			(size 0.4572 0.4572)
			(layers "F.Cu" "F.Mask" "F.Paste")
			(net "P5E_PEX0_STN4_TX_DN<75>")
		)
		(pad "H45" smd circle
			(at 18.999962 -16.150082)
			(size 0.4572 0.4572)
			(layers "F.Cu" "F.Mask" "F.Paste")
			(net "GND")
		)
		(pad "H46" smd circle
			(at 19.949922 -16.150082)
			(size 0.4572 0.4572)
			(layers "F.Cu" "F.Mask" "F.Paste")
			(net "P5E_PEX0_STN4_TX_DN<73>")
		)
		(pad "H47" smd circle
			(at 20.899882 -16.150082)
			(size 0.4572 0.4572)
			(layers "F.Cu" "F.Mask" "F.Paste")
			(net "GND")
		)
		(pad "H48" smd circle
			(at 21.850096 -16.150082)
			(size 0.4572 0.4572)
			(layers "F.Cu" "F.Mask" "F.Paste")
			(net "P5E_PEX0_STN4_TX_DP<70>")
		)
		(pad "H49" smd circle
			(at 22.800056 -16.150082)
			(size 0.4572 0.4572)
			(layers "F.Cu" "F.Mask" "F.Paste")
			(net "P5E_PEX0_STN4_TX_DN<70>")
		)
		(pad "J1" smd circle
			(at -22.800056 -15.200122)
			(size 0.4572 0.4572)
			(layers "F.Cu" "F.Mask" "F.Paste")
			(net "GND")
		)
		(pad "J2" smd circle
			(at -21.850096 -15.200122)
			(size 0.4572 0.4572)
			(layers "F.Cu" "F.Mask" "F.Paste")
			(net "GND")
		)
		(pad "J3" smd circle
			(at -20.899882 -15.200122)
			(size 0.4572 0.4572)
			(layers "F.Cu" "F.Mask" "F.Paste")
			(net "GND")
		)
		(pad "J4" smd circle
			(at -19.949922 -15.200122)
			(size 0.4572 0.4572)
			(layers "F.Cu" "F.Mask" "F.Paste")
			(net "P5E_PEX0_STN7_TX_DP<124>")
		)
		(pad "J5" smd circle
			(at -18.999962 -15.200122)
			(size 0.4572 0.4572)
			(layers "F.Cu" "F.Mask" "F.Paste")
			(net "GND")
		)
		(pad "J6" smd circle
			(at -18.050002 -15.200122)
			(size 0.4572 0.4572)
			(layers "F.Cu" "F.Mask" "F.Paste")
			(net "P5E_PEX0_STN7_TX_DP<126>")
		)
		(pad "J7" smd circle
			(at -17.100042 -15.200122)
			(size 0.4572 0.4572)
			(layers "F.Cu" "F.Mask" "F.Paste")
			(net "GND")
		)
		(pad "J8" smd circle
			(at -16.150082 -15.200122)
			(size 0.4572 0.4572)
			(layers "F.Cu" "F.Mask" "F.Paste")
			(net "P5E_PEX0_STN6_TX_DP<111>")
		)
		(pad "J9" smd circle
			(at -15.200122 -15.200122)
			(size 0.4572 0.4572)
			(layers "F.Cu" "F.Mask" "F.Paste")
			(net "GND")
		)
		(pad "J10" smd circle
			(at -14.249908 -15.200122)
			(size 0.4572 0.4572)
			(layers "F.Cu" "F.Mask" "F.Paste")
			(net "P5E_PEX0_STN6_TX_DP<109>")
		)
		(pad "J11" smd circle
			(at -13.299948 -15.200122)
			(size 0.4572 0.4572)
			(layers "F.Cu" "F.Mask" "F.Paste")
			(net "GND")
		)
		(pad "J12" smd circle
			(at -12.349988 -15.200122)
			(size 0.4572 0.4572)
			(layers "F.Cu" "F.Mask" "F.Paste")
			(net "P5E_PEX0_STN6_TX_DP<107>")
		)
		(pad "J13" smd circle
			(at -11.400028 -15.200122)
			(size 0.4572 0.4572)
			(layers "F.Cu" "F.Mask" "F.Paste")
			(net "GND")
		)
		(pad "J14" smd circle
			(at -10.450068 -15.200122)
			(size 0.4572 0.4572)
			(layers "F.Cu" "F.Mask" "F.Paste")
			(net "P5E_PEX0_STN6_TX_DP<105>")
		)
		(pad "J15" smd circle
			(at -9.500108 -15.200122)
			(size 0.4572 0.4572)
			(layers "F.Cu" "F.Mask" "F.Paste")
			(net "GND")
		)
		(pad "J16" smd circle
			(at -8.549894 -15.200122)
			(size 0.4572 0.4572)
			(layers "F.Cu" "F.Mask" "F.Paste")
			(net "P5E_PEX0_STN6_TX_DP<103>")
		)
		(pad "J17" smd circle
			(at -7.599934 -15.200122)
			(size 0.4572 0.4572)
			(layers "F.Cu" "F.Mask" "F.Paste")
			(net "GND")
		)
		(pad "J18" smd circle
			(at -6.649974 -15.200122)
			(size 0.4572 0.4572)
			(layers "F.Cu" "F.Mask" "F.Paste")
			(net "P5E_PEX0_STN6_TX_DP<101>")
		)
		(pad "J19" smd circle
			(at -5.700014 -15.200122)
			(size 0.4572 0.4572)
			(layers "F.Cu" "F.Mask" "F.Paste")
			(net "GND")
		)
		(pad "J20" smd circle
			(at -4.750054 -15.200122)
			(size 0.4572 0.4572)
			(layers "F.Cu" "F.Mask" "F.Paste")
			(net "P5E_PEX0_STN6_TX_DP<99>")
		)
		(pad "J21" smd circle
			(at -3.800094 -15.200122)
			(size 0.4572 0.4572)
			(layers "F.Cu" "F.Mask" "F.Paste")
			(net "GND")
		)
		(pad "J22" smd circle
			(at -2.84988 -15.200122)
			(size 0.4572 0.4572)
			(layers "F.Cu" "F.Mask" "F.Paste")
			(net "P5E_PEX0_STN6_TX_DP<97>")
		)
		(pad "J23" smd circle
			(at -1.89992 -15.200122)
			(size 0.4572 0.4572)
			(layers "F.Cu" "F.Mask" "F.Paste")
			(net "GND")
		)
		(pad "J24" smd circle
			(at -0.94996 -15.200122)
			(size 0.4572 0.4572)
			(layers "F.Cu" "F.Mask" "F.Paste")
			(net "P5E_PEX0_STN5_TX_DP<80>")
		)
		(pad "J25" smd circle
			(at 0 -15.200122)
			(size 0.4572 0.4572)
			(layers "F.Cu" "F.Mask" "F.Paste")
			(net "GND")
		)
		(pad "J26" smd circle
			(at 0.94996 -15.200122)
			(size 0.4572 0.4572)
			(layers "F.Cu" "F.Mask" "F.Paste")
			(net "P5E_PEX0_STN5_TX_DP<82>")
		)
		(pad "J27" smd circle
			(at 1.89992 -15.200122)
			(size 0.4572 0.4572)
			(layers "F.Cu" "F.Mask" "F.Paste")
			(net "GND")
		)
		(pad "J28" smd circle
			(at 2.84988 -15.200122)
			(size 0.4572 0.4572)
			(layers "F.Cu" "F.Mask" "F.Paste")
			(net "P5E_PEX0_STN5_TX_DP<84>")
		)
		(pad "J29" smd circle
			(at 3.800094 -15.200122)
			(size 0.4572 0.4572)
			(layers "F.Cu" "F.Mask" "F.Paste")
			(net "GND")
		)
		(pad "J30" smd circle
			(at 4.750054 -15.200122)
			(size 0.4572 0.4572)
			(layers "F.Cu" "F.Mask" "F.Paste")
			(net "P5E_PEX0_STN5_TX_DP<86>")
		)
		(pad "J31" smd circle
			(at 5.700014 -15.200122)
			(size 0.4572 0.4572)
			(layers "F.Cu" "F.Mask" "F.Paste")
			(net "GND")
		)
		(pad "J32" smd circle
			(at 6.649974 -15.200122)
			(size 0.4572 0.4572)
			(layers "F.Cu" "F.Mask" "F.Paste")
			(net "P5E_PEX0_STN5_TX_DP<88>")
		)
		(pad "J33" smd circle
			(at 7.599934 -15.200122)
			(size 0.4572 0.4572)
			(layers "F.Cu" "F.Mask" "F.Paste")
			(net "GND")
		)
		(pad "J34" smd circle
			(at 8.549894 -15.200122)
			(size 0.4572 0.4572)
			(layers "F.Cu" "F.Mask" "F.Paste")
			(net "P5E_PEX0_STN5_TX_DP<90>")
		)
		(pad "J35" smd circle
			(at 9.500108 -15.200122)
			(size 0.4572 0.4572)
			(layers "F.Cu" "F.Mask" "F.Paste")
			(net "GND")
		)
		(pad "J36" smd circle
			(at 10.450068 -15.200122)
			(size 0.4572 0.4572)
			(layers "F.Cu" "F.Mask" "F.Paste")
			(net "P5E_PEX0_STN5_TX_DP<92>")
		)
		(pad "J37" smd circle
			(at 11.400028 -15.200122)
			(size 0.4572 0.4572)
			(layers "F.Cu" "F.Mask" "F.Paste")
			(net "GND")
		)
		(pad "J38" smd circle
			(at 12.349988 -15.200122)
			(size 0.4572 0.4572)
			(layers "F.Cu" "F.Mask" "F.Paste")
			(net "P5E_PEX0_STN5_TX_DP<94>")
		)
		(pad "J39" smd circle
			(at 13.299948 -15.200122)
			(size 0.4572 0.4572)
			(layers "F.Cu" "F.Mask" "F.Paste")
			(net "GND")
		)
		(pad "J40" smd circle
			(at 14.249908 -15.200122)
			(size 0.4572 0.4572)
			(layers "F.Cu" "F.Mask" "F.Paste")
			(net "P5E_PEX0_STN4_TX_DP<79>")
		)
		(pad "J41" smd circle
			(at 15.200122 -15.200122)
			(size 0.4572 0.4572)
			(layers "F.Cu" "F.Mask" "F.Paste")
			(net "GND")
		)
		(pad "J42" smd circle
			(at 16.150082 -15.200122)
			(size 0.4572 0.4572)
			(layers "F.Cu" "F.Mask" "F.Paste")
			(net "P5E_PEX0_STN4_TX_DP<77>")
		)
		(pad "J43" smd circle
			(at 17.100042 -15.200122)
			(size 0.4572 0.4572)
			(layers "F.Cu" "F.Mask" "F.Paste")
			(net "GND")
		)
		(pad "J44" smd circle
			(at 18.050002 -15.200122)
			(size 0.4572 0.4572)
			(layers "F.Cu" "F.Mask" "F.Paste")
			(net "P5E_PEX0_STN4_TX_DP<75>")
		)
		(pad "J45" smd circle
			(at 18.999962 -15.200122)
			(size 0.4572 0.4572)
			(layers "F.Cu" "F.Mask" "F.Paste")
			(net "GND")
		)
		(pad "J46" smd circle
			(at 19.949922 -15.200122)
			(size 0.4572 0.4572)
			(layers "F.Cu" "F.Mask" "F.Paste")
			(net "P5E_PEX0_STN4_TX_DP<73>")
		)
		(pad "J47" smd circle
			(at 20.899882 -15.200122)
			(size 0.4572 0.4572)
			(layers "F.Cu" "F.Mask" "F.Paste")
			(net "GND")
		)
		(pad "J48" smd circle
			(at 21.850096 -15.200122)
			(size 0.4572 0.4572)
			(layers "F.Cu" "F.Mask" "F.Paste")
			(net "GND")
		)
		(pad "J49" smd circle
			(at 22.800056 -15.200122)
			(size 0.4572 0.4572)
			(layers "F.Cu" "F.Mask" "F.Paste")
			(net "GND")
		)
		(pad "K1" smd circle
			(at -22.800056 -14.249908)
			(size 0.4572 0.4572)
			(layers "F.Cu" "F.Mask" "F.Paste")
			(net "P5E_PEX0_STN7_RX_DN<121>")
		)
		(pad "K2" smd circle
			(at -21.850096 -14.249908)
			(size 0.4572 0.4572)
			(layers "F.Cu" "F.Mask" "F.Paste")
			(net "P5E_PEX0_STN7_RX_DP<121>")
		)
		(pad "K3" smd circle
			(at -20.899882 -14.249908)
			(size 0.4572 0.4572)
			(layers "F.Cu" "F.Mask" "F.Paste")
			(net "GND")
		)
		(pad "K4" smd circle
			(at -19.949922 -14.249908)
			(size 0.4572 0.4572)
			(layers "F.Cu" "F.Mask" "F.Paste")
			(net "GND")
		)
		(pad "K5" smd circle
			(at -18.999962 -14.249908)
			(size 0.4572 0.4572)
			(layers "F.Cu" "F.Mask" "F.Paste")
			(net "GND")
		)
		(pad "K6" smd circle
			(at -18.050002 -14.249908)
			(size 0.4572 0.4572)
			(layers "F.Cu" "F.Mask" "F.Paste")
			(net "GND")
		)
		(pad "K7" smd circle
			(at -17.100042 -14.249908)
			(size 0.4572 0.4572)
			(layers "F.Cu" "F.Mask" "F.Paste")
			(net "GND")
		)
		(pad "K8" smd circle
			(at -16.150082 -14.249908)
			(size 0.4572 0.4572)
			(layers "F.Cu" "F.Mask" "F.Paste")
			(net "GND")
		)
		(pad "K9" smd circle
			(at -15.200122 -14.249908)
			(size 0.4572 0.4572)
			(layers "F.Cu" "F.Mask" "F.Paste")
			(net "GND")
		)
		(pad "K10" smd circle
			(at -14.249908 -14.249908)
			(size 0.4572 0.4572)
			(layers "F.Cu" "F.Mask" "F.Paste")
			(net "GND")
		)
		(pad "K11" smd circle
			(at -13.299948 -14.249908)
			(size 0.4572 0.4572)
			(layers "F.Cu" "F.Mask" "F.Paste")
			(net "GND")
		)
		(pad "K12" smd circle
			(at -12.349988 -14.249908)
			(size 0.4572 0.4572)
			(layers "F.Cu" "F.Mask" "F.Paste")
			(net "GND")
		)
		(pad "K13" smd circle
			(at -11.400028 -14.249908)
			(size 0.4572 0.4572)
			(layers "F.Cu" "F.Mask" "F.Paste")
			(net "GND")
		)
		(pad "K14" smd circle
			(at -10.450068 -14.249908)
			(size 0.4572 0.4572)
			(layers "F.Cu" "F.Mask" "F.Paste")
			(net "GND")
		)
		(pad "K15" smd circle
			(at -9.500108 -14.249908)
			(size 0.4572 0.4572)
			(layers "F.Cu" "F.Mask" "F.Paste")
			(net "GND")
		)
		(pad "K16" smd circle
			(at -8.549894 -14.249908)
			(size 0.4572 0.4572)
			(layers "F.Cu" "F.Mask" "F.Paste")
			(net "GND")
		)
		(pad "K17" smd circle
			(at -7.599934 -14.249908)
			(size 0.4572 0.4572)
			(layers "F.Cu" "F.Mask" "F.Paste")
			(net "GND")
		)
		(pad "K18" smd circle
			(at -6.649974 -14.249908)
			(size 0.4572 0.4572)
			(layers "F.Cu" "F.Mask" "F.Paste")
			(net "GND")
		)
		(pad "K19" smd circle
			(at -5.700014 -14.249908)
			(size 0.4572 0.4572)
			(layers "F.Cu" "F.Mask" "F.Paste")
			(net "GND")
		)
		(pad "K20" smd circle
			(at -4.750054 -14.249908)
			(size 0.4572 0.4572)
			(layers "F.Cu" "F.Mask" "F.Paste")
			(net "GND")
		)
		(pad "K21" smd circle
			(at -3.800094 -14.249908)
			(size 0.4572 0.4572)
			(layers "F.Cu" "F.Mask" "F.Paste")
			(net "GND")
		)
		(pad "K22" smd circle
			(at -2.84988 -14.249908)
			(size 0.4572 0.4572)
			(layers "F.Cu" "F.Mask" "F.Paste")
			(net "GND")
		)
	)
)
